G04 ================== begin FILE IDENTIFICATION RECORD ==================*
G04 Layout Name:  9127_F0T_Expander_BD_F_v02_0110_1240.brd*
G04 Film Name:    outline*
G04 File Format:  Gerber RS274X*
G04 File Origin:  Cadence Allegro 17.2-S081*
G04 Origin Date:  Wed Jan 11 16:06:34 2023*
G04 *
G04 Layer:  BOARD GEOMETRY/DESIGN_OUTLINE*
G04 Layer:  BOARD GEOMETRY/CUTOUT*
G04 *
G04 Offset:    (0.00 0.00)*
G04 Mirror:    No*
G04 Mode:      Positive*
G04 Rotation:  0*
G04 FullContactRelief:  No*
G04 UndefLineWidth:     6.00*
G04 ================== end FILE IDENTIFICATION RECORD ====================*
%FSLAX25Y25*MOIN*%
%IR0*IPPOS*OFA0.00000B0.00000*MIA0B0*SFA1.00000B1.00000*%
%ADD10C,.006*%
G75*
%LPD*%
G75*
G54D10*
G01X795131Y1645405D02*
G03X789296Y1647992I-5835J-5287D01*
G01X7874D01*
G03X0Y1640118I0J-7874D01*
G01Y970427D01*
G03X2306Y964859I7874J0D01*
G01X12654Y954511D01*
G02X14961Y948943I-5568J-5569D01*
G01Y344836D01*
G02X12654Y339269I-7873J1D01*
G01X2306Y328920D01*
G03X0Y323353I5567J-5567D01*
G01Y7874D01*
G03X7874Y0I7874J0D01*
G01X23484D01*
G03X31358Y7874I0J7874D01*
G01Y46654D01*
G02X35295Y50591I3937J0D01*
G01X66791D01*
G02X70728Y46654I0J-3937D01*
G01Y7874D01*
G03X78602Y0I7874J0D01*
G01X125846D01*
G03X133720Y7874I0J7874D01*
G01Y46654D01*
G02X137657Y50591I3937J0D01*
G01X169154D01*
G02X173091Y46654I0J-3937D01*
G01Y7874D01*
G03X180965Y0I7874J0D01*
G01X228209D01*
G03X236083Y7874I0J7874D01*
G01Y46654D01*
G02X240020Y50591I3937J0D01*
G01X271516D01*
G02X275453Y46654I0J-3937D01*
G01Y7874D01*
G03X283327Y0I7874J0D01*
G01X330571D01*
G03X338445Y7874I0J7874D01*
G01Y46654D01*
G02X342382Y50591I3937J0D01*
G01X373878D01*
G02X377815Y46654I0J-3937D01*
G01Y7874D01*
G03X385689Y0I7874J0D01*
G01X480571D01*
G03X488445Y7874I0J7874D01*
G01Y46654D01*
G02X492382Y50591I3937J0D01*
G01X523878D01*
G02X527815Y46654I0J-3937D01*
G01Y7874D01*
G03X535689Y0I7874J0D01*
G01X582933D01*
G03X590807Y7874I0J7874D01*
G01Y46654D01*
G02X594744Y50591I3937J0D01*
G01X626240D01*
G02X630177Y46654I0J-3937D01*
G01Y7874D01*
G03X638051Y0I7874J0D01*
G01X685295D01*
G03X693169Y7874I0J7874D01*
G01Y46654D01*
G02X697106Y50591I3937J0D01*
G01X728602D01*
G02X732539Y46654I0J-3937D01*
G01Y7874D01*
G03X740413Y0I7874J0D01*
G01X787657D01*
G03X795531Y7874I0J7874D01*
G01Y46654D01*
G02X799469Y50591I3937J0D01*
G01X830965D01*
G02X834902Y46654I0J-3937D01*
G01Y7874D01*
G03X842776Y0I7874J0D01*
G01X937657D01*
G03X945531Y7874I0J7874D01*
G01Y46654D01*
G02X949469Y50591I3938J0D01*
G01X980965D01*
G02X984902Y46654I0J-3937D01*
G01Y7874D01*
G03X992776Y0I7874J0D01*
G01X1040020D01*
G03X1047894Y7874I0J7874D01*
G01Y46654D01*
G02X1051831Y50591I3937J0D01*
G01X1083327D01*
G02X1087264Y46654I0J-3937D01*
G01Y7874D01*
G03X1095138Y0I7874J0D01*
G01X1142382D01*
G03X1150256Y7874I0J7874D01*
G01Y46654D01*
G02X1154193Y50591I3937J0D01*
G01X1185689D01*
G02X1189626Y46654I0J-3937D01*
G01Y7874D01*
G03X1197500Y0I7874J0D01*
G01X1244744D01*
G03X1252618Y7874I0J7874D01*
G01Y46654D01*
G02X1256555Y50591I3937J0D01*
G01X1288051D01*
G02X1291988Y46654I0J-3937D01*
G01Y7874D01*
G03X1299862Y0I7874J0D01*
G01X1394744D01*
G03X1402618Y7874I0J7874D01*
G01Y46654D01*
G02X1406555Y50591I3937J0D01*
G01X1438051D01*
G02X1441988Y46654I0J-3937D01*
G01Y7874D01*
G03X1449862Y0I7874J0D01*
G01X1497106D01*
G03X1504980Y7874I0J7874D01*
G01Y46654D01*
G02X1508917Y50591I3937J0D01*
G01X1540413D01*
G02X1544350Y46654I0J-3937D01*
G01Y7874D01*
G03X1552224Y0I7874J0D01*
G01X1599469D01*
G03X1607343Y7874I0J7874D01*
G01Y46654D01*
G02X1611280Y50591I3937J0D01*
G01X1642776D01*
G02X1646713Y46654I0J-3937D01*
G01Y7874D01*
G03X1654587Y0I7874J0D01*
G01X1701831D01*
G03X1709705Y7874I0J7874D01*
G01Y46654D01*
G02X1713642Y50591I3937J0D01*
G01X1745138D01*
G02X1749075Y46654I0J-3937D01*
G01Y7874D01*
G03X1756949Y0I7874J0D01*
G01X1833071D01*
G03X1840945Y7874I0J7874D01*
G01Y323353D01*
G03X1838639Y328920I-7873J0D01*
G01X1828291Y339269D01*
G02X1825984Y344836I5566J5568D01*
G01Y948943D01*
G02X1828291Y954511I7875J-1D01*
G01X1838639Y964859D01*
G03X1840945Y970427I-5568J5568D01*
G01Y1640118D01*
G03X1833071Y1647992I-7874J0D01*
G01X1081727D01*
G03X1075892Y1645405I0J-7874D01*
G02X1070057Y1642819I-5834J5288D01*
G01X800966D01*
G02X795131Y1645405I-1J7874D01*
G01X7480Y1226024D02*
G02X20079I6299J0D01*
G02X7480I-6299J0D01*
G01X20472Y1573425D02*
X26772D01*
G02Y1561220I0J-6103D01*
G01X20472D01*
G02Y1573425I0J6102D01*
G01X12598Y1604724D02*
G02X34646I11024J0D01*
G02X12598I-11024J0D01*
G01X24882Y81575D02*
G02X32756I3937J0D01*
G02X24882I-3937J0D01*
G01X51181Y765197D02*
G02X73228I11023J0D01*
G02X51181I-11024J0D01*
G01X62992Y333465D02*
G02X85039I11024J0D01*
G02X62992I-11023J0D01*
G01X69370Y61614D02*
G02X77244I3937J0D01*
G02X69370I-3937J0D01*
G01X73031Y1186654D02*
G02X85630I6299J0D01*
G02X73031I-6300J0D01*
G01X91201Y70866D02*
G02X113248I11024J0D01*
G02X91201I-11023J0D01*
G01X107874Y1066535D02*
G02X125591I8859J0D01*
G02X107874I-8858J0D01*
G01Y1263386D02*
G02X125591I8859J0D01*
G02X107874I-8858J0D01*
G01X127244Y81575D02*
G02X135118I3937J0D01*
G02X127244I-3937J0D01*
G01X171732Y61614D02*
G02X179606I3937J0D01*
G02X171732I-3937J0D01*
G01X229606Y81575D02*
G02X237480I3937J0D01*
G02X229606I-3937J0D01*
G01X241644Y1580079D02*
G02X229144I-6250J0D01*
G02X241644I6250J0D01*
G01X241683Y1606142D02*
G02X229183I-6250J0D01*
G02X241683I6250J0D01*
G01X241644Y1626339D02*
G02X229144I-6250J0D01*
G02X241644I6250J0D01*
G01X274094Y61614D02*
G02X281969I3938J0D01*
G02X274094I-3937J0D01*
G01X331969Y81575D02*
G02X339843I3937J0D01*
G02X331969I-3937J0D01*
G01X344094Y1066535D02*
G02X361811I8858J0D01*
G02X344094I-8859J0D01*
G01Y1263386D02*
G02X361811I8858J0D01*
G02X344094I-8859J0D01*
G01X376457Y61614D02*
G02X384331I3937J0D01*
G02X376457I-3937J0D01*
G01X384055Y1141024D02*
G02X396654I6299J0D01*
G02X384055I-6299J0D01*
G01X398465Y1604724D02*
G02X420512I11024J0D01*
G02X398465I-11023J0D01*
G01X422106Y70866D02*
G02X444154I11024J0D01*
G02X422106I-11024J0D01*
G01X452362Y286220D02*
G02X474409I11023J0D01*
G02X452362I-11024J0D01*
G01Y765197D02*
G02X474409I11023J0D01*
G02X452362I-11024J0D01*
G01X481969Y81575D02*
G02X489843I3937J0D01*
G02X481969I-3937J0D01*
G01X526457Y61614D02*
G02X534331I3937J0D01*
G02X526457I-3937J0D01*
G01X530118Y1086654D02*
G02X542717I6299J0D01*
G02X530118I-6299J0D01*
G01X564961Y1066535D02*
G02X582677I8858J0D01*
G02X564961I-8858J0D01*
G01Y1263386D02*
G02X582677I8858J0D01*
G02X564961I-8858J0D01*
G01X584331Y81575D02*
G02X592205I3937J0D01*
G02X584331I-3937J0D01*
G01X588140Y1580079D02*
G02X575640I-6250J0D01*
G02X588140I6250J0D01*
G01Y1606142D02*
G02X575640I-6250J0D01*
G02X588140I6250J0D01*
G01Y1626339D02*
G02X575640I-6250J0D01*
G02X588140I6250J0D01*
G01X628819Y61614D02*
G02X636693I3937J0D01*
G02X628819I-3937J0D01*
G01X650650Y23622D02*
G02X672697I11023J0D01*
G02X650650I-11024J0D01*
G01X686693Y81575D02*
G02X694567I3937J0D01*
G02X686693I-3937J0D01*
G01X731181Y61614D02*
G02X739055I3937J0D01*
G02X731181I-3937J0D01*
G01X763780Y1490945D02*
G02X777165I6693J0D01*
G02X763780I-6692J0D01*
G01X774016Y1547638D02*
G02X796063I11024J0D01*
G02X774016I-11023J0D01*
G01X789055Y81575D02*
G02X796929I3937J0D01*
G02X789055I-3937J0D01*
G01X813386Y388583D02*
G02X826772I6693J0D01*
G02X813386I-6693J0D01*
G01X801181Y1066535D02*
G02X818898I8859J0D01*
G02X801181I-8858J0D01*
G01Y1263386D02*
G02X818898I8859J0D01*
G02X801181I-8858J0D01*
G01X833543Y61614D02*
G02X841417I3937J0D01*
G02X833543I-3937J0D01*
G01X841173Y1367717D02*
G02X857709I8268J0D01*
G02X841173I-8268J0D01*
G01X847992Y1225118D02*
G02X860591I6300J0D01*
G02X847992I-6299J0D01*
G01X879193Y23622D02*
G02X901240I11024J0D01*
G02X879193I-11023J0D01*
G01X909449Y765197D02*
G02X931496I11023J0D01*
G02X909449I-11023J0D01*
G01X939055Y81575D02*
G02X946929I3937J0D01*
G02X939055I-3937J0D01*
G01X983543Y61614D02*
G02X991417I3937J0D01*
G02X983543I-3937J0D01*
G01X987205Y1170748D02*
G02X999803I6299J0D01*
G02X987205I-6299J0D01*
G01X1014173Y388583D02*
G02X1027559I6693J0D01*
G02X1014173I-6693J0D01*
G01X1022047Y1066535D02*
G02X1039764I8859J0D01*
G02X1022047I-8858J0D01*
G01Y1263386D02*
G02X1039764I8859J0D01*
G02X1022047I-8858J0D01*
G01X1041417Y81575D02*
G02X1049291I3937J0D01*
G02X1041417I-3937J0D01*
G01X1044882Y1547638D02*
G02X1066929I11024J0D01*
G02X1044882I-11024J0D01*
G01X1063780Y1490945D02*
G02X1077165I6692J0D01*
G02X1063780I-6692J0D01*
G01X1085906Y61614D02*
G02X1093780I3937J0D01*
G02X1085906I-3937J0D01*
G01X1107736Y23622D02*
G02X1129783I11023J0D01*
G02X1107736I-11023J0D01*
G01X1143780Y81575D02*
G02X1151654I3937J0D01*
G02X1143780I-3937J0D01*
G01X1188268Y61614D02*
G02X1196142I3937J0D01*
G02X1188268I-3937J0D01*
G01X1246142Y81575D02*
G02X1254016I3937J0D01*
G02X1246142I-3937J0D01*
G01X1265305Y1580079D02*
G02X1252805I-6250J0D01*
G02X1265305I6250J0D01*
G01Y1606142D02*
G02X1252805I-6250J0D01*
G02X1265305I6250J0D01*
G01Y1626339D02*
G02X1252805I-6250J0D01*
G02X1265305I6250J0D01*
G01X1258268Y1066535D02*
G02X1275984I8858J0D01*
G02X1258268I-8858J0D01*
G01Y1263386D02*
G02X1275984I8858J0D01*
G02X1258268I-8858J0D01*
G01X1290630Y61614D02*
G02X1298504I3937J0D01*
G02X1290630I-3937J0D01*
G01X1298228Y1141024D02*
G02X1310827I6299J0D01*
G02X1298228I-6300J0D01*
G01X1336280Y70866D02*
G02X1358327I11023J0D01*
G02X1336280I-11024J0D01*
G01X1366535Y286220D02*
G02X1388583I11024J0D01*
G02X1366535I-11024J0D01*
G01Y765197D02*
G02X1388583I11024J0D01*
G02X1366535I-11024J0D01*
G01X1396142Y81575D02*
G02X1404016I3937J0D01*
G02X1396142I-3937J0D01*
G01X1420433Y1604724D02*
G02X1442480I11023J0D01*
G02X1420433I-11023J0D01*
G01X1440630Y61614D02*
G02X1448504I3937J0D01*
G02X1440630I-3937J0D01*
G01X1444291Y1086654D02*
G02X1456890I6300J0D01*
G02X1444291I-6299J0D01*
G01X1479134Y1066535D02*
G02X1496850I8858J0D01*
G02X1479134I-8858J0D01*
G01Y1263386D02*
G02X1496850I8858J0D01*
G02X1479134I-8858J0D01*
G01X1498504Y81575D02*
G02X1506378I3937J0D01*
G02X1498504I-3937J0D01*
G01X1542992Y61614D02*
G02X1550866I3937J0D01*
G02X1542992I-3937J0D01*
G01X1564823Y23622D02*
G02X1586870I11024J0D01*
G02X1564823I-11023J0D01*
G01X1600866Y81575D02*
G02X1608740I3937J0D01*
G02X1600866I-3937J0D01*
G01X1611801Y1580079D02*
G02X1599301I-6250J0D01*
G02X1611801I6250J0D01*
G01X1611762Y1606142D02*
G02X1599262I-6250J0D01*
G02X1611762I6250J0D01*
G01X1611801Y1626339D02*
G02X1599301I-6250J0D01*
G02X1611801I6250J0D01*
G01X1645354Y61614D02*
G02X1653228I3937J0D01*
G02X1645354I-3937J0D01*
G01X1703228Y81575D02*
G02X1711102I3937J0D01*
G02X1703228I-3937J0D01*
G01X1715354Y1066535D02*
G02X1733071I8859J0D01*
G02X1715354I-8858J0D01*
G01Y1263386D02*
G02X1733071I8859J0D01*
G02X1715354I-8858J0D01*
G01X1747717Y61614D02*
G02X1755591I3937J0D01*
G02X1747717I-3937J0D01*
G01X1755906Y333465D02*
G02X1777953I11023J0D01*
G02X1755906I-11023J0D01*
G01X1755315Y1215000D02*
G02X1767913I6299J0D01*
G02X1755315I-6299J0D01*
G01X1767717Y765197D02*
G02X1789764I11023J0D01*
G02X1767717I-11023J0D01*
G01X1783986Y23622D02*
G02X1806033I11023J0D01*
G02X1783986I-11023J0D01*
G01X1823425Y59843D02*
Y53543D01*
G02X1811220I-6103J0D01*
G01Y59843D01*
G02X1823425I6102J0D01*
G01X1820866Y1235630D02*
G02X1833465I6299J0D01*
G02X1820866I-6300J0D01*
G01X1811220Y1567323D02*
G02X1823425I6102J0D01*
G02X1811220I-6103J0D01*
G01X1806299Y1604724D02*
G02X1828346I11023J0D01*
G02X1806299I-11023J0D01*
M02*
